(kicad_pcb
	(version 20260206)
	(generator "pcbnew")
	(generator_version "10.0")
	(general
		(thickness 1.6)
		(legacy_teardrops no)
	)
	(paper "A4")
	(title_block
		(title "Bryce Canyon_IOM_M2_16342-2_OCP.brd")
		(comment 1 "Bryce Canyon / footprints 712-718 of 1146")
	)
	(layers
		(0 "F.Cu" signal "TOP")
		(4 "In1.Cu" signal "L2GND")
		(6 "In2.Cu" signal "L3")
		(8 "In3.Cu" signal "L4VCC")
		(10 "In4.Cu" signal "L5VCC")
		(12 "In5.Cu" signal "L6")
		(14 "In6.Cu" signal "L7GND")
		(2 "B.Cu" signal "BOTTOM")
		(9 "F.Adhes" user "F.Adhesive")
		(11 "B.Adhes" user "B.Adhesive")
		(13 "F.Paste" user "Package Geometry/Pastemask Top")
		(15 "B.Paste" user "Package Geometry/Pastemask Bottom")
		(5 "F.SilkS" user "Ref Des/Silkscreen Top")
		(7 "B.SilkS" user "Ref Des/Silkscreen Bottom")
		(1 "F.Mask" user "Board Geometry/Soldermask Top")
		(3 "B.Mask" user "Board Geometry/Soldermask Bottom")
		(17 "Dwgs.User" user "User.Drawings")
		(19 "Cmts.User" user "User.Comments")
		(21 "Eco1.User" user "User.Eco1")
		(23 "Eco2.User" user "User.Eco2")
		(25 "Edge.Cuts" user "Board Geometry/Outline")
		(27 "Margin" user)
		(31 "F.CrtYd" user "Package Geometry/Place Bound Top")
		(29 "B.CrtYd" user "Package Geometry/Place Bound Bottom")
		(35 "F.Fab" user "Ref Des/Assembly Top")
		(33 "B.Fab" user "Ref Des/Assembly Bottom")
	)
	(footprint ""
		(layer "F.Cu")
		(at 87.976964 -151.068786 90)
		(property "Reference" "R92"
			(at 0 0 90)
			(layer "F.SilkS")
			(hide yes)
			(effects
				(font
					(size 1.27 1.27)
				)
			)
		)
		(property "Value" "0R2J-2-GP"
			(at 0.064008 -3.993896 90)
			(unlocked yes)
			(layer "F.Fab")
			(hide yes)
			(effects
				(font
					(size 1.016 1.016)
					(thickness 0.1524)
				)
			)
		)
		(property "Device Type" "R402H16"
			(at 0.064008 -5.517896 90)
			(unlocked yes)
			(layer "F.Fab")
			(hide yes)
			(effects
				(font
					(size 1.016 1.016)
					(thickness 0.1524)
				)
			)
		)
		(duplicate_pad_numbers_are_jumpers no)
		(fp_line
			(start 0.508 -0.9398)
			(end -0.508 -0.9398)
			(stroke
				(width 0.1524)
				(type default)
			)
			(layer "F.SilkS")
		)
		(fp_line
			(start -0.508 -0.9398)
			(end -0.508 0.9398)
			(stroke
				(width 0.1524)
				(type default)
			)
			(layer "F.SilkS")
		)
		(fp_rect
			(start -0.508 0.9398)
			(end 0.508 -0.9398)
			(stroke
				(width 0)
				(type default)
			)
			(fill no)
			(layer "F.CrtYd")
		)
		(fp_rect
			(start -0.508 0.9398)
			(end 0.508 -0.9398)
			(stroke
				(width 0)
				(type default)
			)
			(fill no)
			(layer "F.Fab")
		)
		(pad "1" smd custom
			(at 0 -0.4445 90)
			(size 0.1397 0.1397)
			(layers "F.Cu" "F.Mask" "F.Paste")
			(net "I2C_BMC_COMP_SCL_R")
			(options
				(clearance outline)
				(anchor circle)
			)
			(primitives
				(gr_poly
					(pts
						(arc
							(start -0.1778 -0.2794)
							(mid -0.249642 -0.249642)
							(end -0.2794 -0.1778)
						)
						(arc
							(start -0.2794 0.1778)
							(mid -0.249642 0.249642)
							(end -0.1778 0.2794)
						)
						(arc
							(start 0.1778 0.2794)
							(mid 0.249642 0.249642)
							(end 0.2794 0.1778)
						)
						(arc
							(start 0.2794 -0.1778)
							(mid 0.249642 -0.249642)
							(end 0.1778 -0.2794)
						)
					)
					(width 0)
					(fill yes)
				)
			)
		)
		(pad "2" smd custom
			(at 0 0.4445 90)
			(size 0.1397 0.1397)
			(layers "F.Cu" "F.Mask" "F.Paste")
			(net "I2C_BMC_COMP_SCL")
			(options
				(clearance outline)
				(anchor circle)
			)
			(primitives
				(gr_poly
					(pts
						(arc
							(start -0.1778 -0.2794)
							(mid -0.249642 -0.249642)
							(end -0.2794 -0.1778)
						)
						(arc
							(start -0.2794 0.1778)
							(mid -0.249642 0.249642)
							(end -0.1778 0.2794)
						)
						(arc
							(start 0.1778 0.2794)
							(mid 0.249642 0.249642)
							(end 0.2794 0.1778)
						)
						(arc
							(start 0.2794 -0.1778)
							(mid 0.249642 -0.249642)
							(end 0.1778 -0.2794)
						)
					)
					(width 0)
					(fill yes)
				)
			)
		)
	)
	(footprint ""
		(layer "F.Cu")
		(at 78.122018 -70.952868 90)
		(property "Reference" "VIA1"
			(at 0 0 90)
			(layer "F.SilkS")
			(hide yes)
			(effects
				(font
					(size 1.27 1.27)
				)
			)
		)
		(property "Value" "85OHM-8L-1D6MM-L16L18-GP"
			(at 4.064 0.6096 90)
			(unlocked yes)
			(layer "F.Fab")
			(hide yes)
			(effects
				(font
					(size 1.016 1.016)
					(thickness 0.1524)
				)
			)
		)
		(property "Device Type" "VIA-PCIE-4P-368076"
			(at 4.064 -0.9144 90)
			(unlocked yes)
			(layer "F.Fab")
			(hide yes)
			(effects
				(font
					(size 1.016 1.016)
					(thickness 0.1524)
				)
			)
		)
		(duplicate_pad_numbers_are_jumpers no)
		(fp_rect
			(start -1.8415 0.381)
			(end 1.8415 -0.381)
			(stroke
				(width 0)
				(type default)
			)
			(fill no)
			(layer "F.CrtYd")
		)
		(fp_rect
			(start -1.8415 0.381)
			(end 1.8415 -0.381)
			(stroke
				(width 0)
				(type default)
			)
			(fill no)
			(layer "F.Fab")
		)
		(pad "1" thru_hole circle
			(at -1.4605 0 90)
			(size 0.508 0.508)
			(drill 0.254)
			(layers "*.Cu" "*.Mask")
			(remove_unused_layers no)
			(net "GND")
			(clearance 0.127)
			(thermal_gap 0.127)
		)
		(pad "2" thru_hole circle
			(at -0.4445 0 90)
			(size 0.508 0.508)
			(drill 0.254)
			(layers "*.Cu" "*.Mask")
			(remove_unused_layers no)
			(net "PCIE_COMP_TO_IOM_16_DP")
			(clearance 0.127)
			(thermal_gap 0.127)
		)
		(pad "3" thru_hole circle
			(at 0.4445 0 90)
			(size 0.508 0.508)
			(drill 0.254)
			(layers "*.Cu" "*.Mask")
			(remove_unused_layers no)
			(net "PCIE_COMP_TO_IOM_16_DN")
			(clearance 0.127)
			(thermal_gap 0.127)
		)
		(pad "4" thru_hole circle
			(at 1.4605 0 90)
			(size 0.508 0.508)
			(drill 0.254)
			(layers "*.Cu" "*.Mask")
			(remove_unused_layers no)
			(net "GND")
			(clearance 0.127)
			(thermal_gap 0.127)
		)
	)
	(footprint ""
		(layer "F.Cu")
		(at 76.916026 -134.669276 90)
		(property "Reference" "U19"
			(at 0 0 90)
			(layer "F.SilkS")
			(hide yes)
			(effects
				(font
					(size 1.27 1.27)
				)
			)
		)
		(property "Value" "SN74LVC1G74DCUT-GP"
			(at 0 -11.1252 90)
			(unlocked yes)
			(layer "F.Fab")
			(hide yes)
			(effects
				(font
					(size 1.016 1.016)
					(thickness 0.1524)
				)
			)
		)
		(property "Device Type" "SSOIC8-4H36"
			(at 0 -12.6492 90)
			(unlocked yes)
			(layer "F.Fab")
			(hide yes)
			(effects
				(font
					(size 1.016 1.016)
					(thickness 0.1524)
				)
			)
		)
		(duplicate_pad_numbers_are_jumpers no)
		(fp_line
			(start 1.2573 -2.1844)
			(end 1.2573 2.1844)
			(stroke
				(width 0.1524)
				(type default)
			)
			(layer "F.SilkS")
		)
		(fp_line
			(start -1.2573 -2.1844)
			(end 1.2573 -2.1844)
			(stroke
				(width 0.1524)
				(type default)
			)
			(layer "F.SilkS")
		)
		(fp_line
			(start -1.2192 -0.3556)
			(end -0.9017 -0.0381)
			(stroke
				(width 0.1524)
				(type default)
			)
			(layer "F.SilkS")
		)
		(fp_line
			(start -1.2573 -0.3556)
			(end -1.2192 -0.3556)
			(stroke
				(width 0.1524)
				(type default)
			)
			(layer "F.SilkS")
		)
		(fp_line
			(start -0.9017 -0.0381)
			(end -1.2065 0.2667)
			(stroke
				(width 0.1524)
				(type default)
			)
			(layer "F.SilkS")
		)
		(fp_line
			(start -1.2065 0.2667)
			(end -1.27 0.2667)
			(stroke
				(width 0.1524)
				(type default)
			)
			(layer "F.SilkS")
		)
		(fp_line
			(start -1.2954 0.4572)
			(end -1.2954 2.159)
			(stroke
				(width 0.4064)
				(type default)
			)
			(layer "F.SilkS")
		)
		(fp_line
			(start 1.2573 2.1844)
			(end -1.2573 2.1844)
			(stroke
				(width 0.1524)
				(type default)
			)
			(layer "F.SilkS")
		)
		(fp_line
			(start -1.2573 2.1844)
			(end -1.2573 -2.1844)
			(stroke
				(width 0.1524)
				(type default)
			)
			(layer "F.SilkS")
		)
		(fp_poly
			(pts
				(xy -1.5113 2.4384) (xy 1.5113 2.4384) (xy 1.5113 -2.4384) (xy -1.5113 -2.4384)
			)
			(stroke
				(width 0)
				(type default)
			)
			(fill no)
			(layer "F.CrtYd")
		)
		(fp_poly
			(pts
				(xy -1.5113 -2.4384) (xy 1.5113 -2.4384) (xy 1.5113 2.4384) (xy -1.5113 2.4384)
			)
			(stroke
				(width 0)
				(type default)
			)
			(fill no)
			(layer "F.Fab")
		)
		(pad "1" smd rect
			(at -0.75057 1.1684 90)
			(size 0.3048 1.524)
			(layers "F.Cu" "F.Mask" "F.Paste")
			(net "DEBUG_HDR_UART_SEL")
		)
		(pad "2" smd rect
			(at -0.25019 1.1684 90)
			(size 0.3048 1.524)
			(layers "F.Cu" "F.Mask" "F.Paste")
			(net "D_FLIP_D")
		)
		(pad "3" smd rect
			(at 0.25019 1.1684 90)
			(size 0.3048 1.524)
			(layers "F.Cu" "F.Mask" "F.Paste")
			(net "D_FLIP_Q#")
		)
		(pad "4" smd rect
			(at 0.75057 1.1684 90)
			(size 0.3048 1.524)
			(layers "F.Cu" "F.Mask" "F.Paste")
			(net "GND")
		)
		(pad "5" smd rect
			(at 0.75057 -1.1684 90)
			(size 0.3048 1.524)
			(layers "F.Cu" "F.Mask" "F.Paste")
			(net "D_FLIP_Q")
		)
		(pad "6" smd rect
			(at 0.25019 -1.1684 90)
			(size 0.3048 1.524)
			(layers "F.Cu" "F.Mask" "F.Paste")
			(net "D_FLIP_CLR#")
		)
		(pad "7" smd rect
			(at -0.25019 -1.1684 90)
			(size 0.3048 1.524)
			(layers "F.Cu" "F.Mask" "F.Paste")
			(net "D_FLIP_PRE#")
		)
		(pad "8" smd rect
			(at -0.75057 -1.1684 90)
			(size 0.3048 1.524)
			(layers "F.Cu" "F.Mask" "F.Paste")
			(net "P3V3_STBY")
		)
	)
	(footprint ""
		(layer "B.Cu")
		(at 14.4272 -146.2659 90)
		(property "Reference" "R210"
			(at 0 0 90)
			(layer "B.SilkS")
			(hide yes)
			(effects
				(font
					(size 1.27 1.27)
				)
				(justify mirror)
			)
		)
		(property "Value" "120R2F-GP"
			(at -0.064008 -3.993896 90)
			(unlocked yes)
			(layer "B.Fab")
			(hide yes)
			(effects
				(font
					(size 1.016 1.016)
					(thickness 0.1524)
				)
				(justify mirror)
			)
		)
		(property "Device Type" "R402H16"
			(at -0.064008 -5.517896 90)
			(unlocked yes)
			(layer "B.Fab")
			(hide yes)
			(effects
				(font
					(size 1.016 1.016)
					(thickness 0.1524)
				)
				(justify mirror)
			)
		)
		(duplicate_pad_numbers_are_jumpers no)
		(fp_line
			(start 0.508 -0.9398)
			(end 0.508 0.9398)
			(stroke
				(width 0.1524)
				(type default)
			)
			(layer "B.SilkS")
		)
		(fp_line
			(start -0.508 -0.9398)
			(end 0.508 -0.9398)
			(stroke
				(width 0.1524)
				(type default)
			)
			(layer "B.SilkS")
		)
		(fp_rect
			(start 0.508 0.9398)
			(end -0.508 -0.9398)
			(stroke
				(width 0)
				(type default)
			)
			(fill no)
			(layer "B.CrtYd")
		)
		(fp_rect
			(start 0.508 0.9398)
			(end -0.508 -0.9398)
			(stroke
				(width 0)
				(type default)
			)
			(fill no)
			(layer "B.Fab")
		)
		(pad "1" smd custom
			(at 0 -0.4445 270)
			(size 0.1397 0.1397)
			(layers "B.Cu" "B.Mask" "B.Paste")
			(net "MEMCKE")
			(options
				(clearance outline)
				(anchor circle)
			)
			(primitives
				(gr_poly
					(pts
						(arc
							(start -0.1778 0.2794)
							(mid -0.249642 0.249642)
							(end -0.2794 0.1778)
						)
						(arc
							(start -0.2794 -0.1778)
							(mid -0.249642 -0.249642)
							(end -0.1778 -0.2794)
						)
						(arc
							(start 0.1778 -0.2794)
							(mid 0.249642 -0.249642)
							(end 0.2794 -0.1778)
						)
						(arc
							(start 0.2794 0.1778)
							(mid 0.249642 0.249642)
							(end 0.1778 0.2794)
						)
					)
					(width 0)
					(fill yes)
				)
			)
		)
		(pad "2" smd custom
			(at 0 0.4445 270)
			(size 0.1397 0.1397)
			(layers "B.Cu" "B.Mask" "B.Paste")
			(net "P1V2_STBY")
			(options
				(clearance outline)
				(anchor circle)
			)
			(primitives
				(gr_poly
					(pts
						(arc
							(start -0.1778 0.2794)
							(mid -0.249642 0.249642)
							(end -0.2794 0.1778)
						)
						(arc
							(start -0.2794 -0.1778)
							(mid -0.249642 -0.249642)
							(end -0.1778 -0.2794)
						)
						(arc
							(start 0.1778 -0.2794)
							(mid 0.249642 -0.249642)
							(end 0.2794 -0.1778)
						)
						(arc
							(start 0.2794 0.1778)
							(mid 0.249642 0.249642)
							(end 0.1778 0.2794)
						)
					)
					(width 0)
					(fill yes)
				)
			)
		)
	)
	(footprint ""
		(layer "B.Cu")
		(at 176.197768 -130.724148 180)
		(property "Reference" "C630"
			(at 0 0 0)
			(layer "B.SilkS")
			(hide yes)
			(effects
				(font
					(size 1.27 1.27)
				)
				(justify mirror)
			)
		)
		(property "Value" "SCD1U16V2KX-3GP"
			(at -1.1811 -2.7051 180)
			(unlocked yes)
			(layer "B.Fab")
			(hide yes)
			(effects
				(font
					(size 1.016 1.016)
					(thickness 0.1524)
				)
				(justify mirror)
			)
		)
		(property "Device Type" "C402H22"
			(at -1.1811 -4.2291 180)
			(unlocked yes)
			(layer "B.Fab")
			(hide yes)
			(effects
				(font
					(size 1.016 1.016)
					(thickness 0.1524)
				)
				(justify mirror)
			)
		)
		(duplicate_pad_numbers_are_jumpers no)
		(fp_rect
			(start 0.4318 0.9525)
			(end -0.4318 -0.9525)
			(stroke
				(width 0)
				(type default)
			)
			(fill no)
			(layer "B.CrtYd")
		)
		(fp_rect
			(start 0.4318 0.9525)
			(end -0.4318 -0.9525)
			(stroke
				(width 0)
				(type default)
			)
			(fill no)
			(layer "B.Fab")
		)
		(pad "1" smd custom
			(at 0 -0.4445)
			(size 0.1524 0.1524)
			(layers "B.Cu" "B.Mask" "B.Paste")
			(net "P3V3_M2")
			(options
				(clearance outline)
				(anchor circle)
			)
			(primitives
				(gr_poly
					(pts
						(arc
							(start 0.3048 0.2032)
							(mid 0.275042 0.275042)
							(end 0.2032 0.3048)
						)
						(arc
							(start -0.2032 0.3048)
							(mid -0.275042 0.275042)
							(end -0.3048 0.2032)
						)
						(arc
							(start -0.3048 -0.2032)
							(mid -0.275042 -0.275042)
							(end -0.2032 -0.3048)
						)
						(arc
							(start 0.2032 -0.3048)
							(mid 0.275042 -0.275042)
							(end 0.3048 -0.2032)
						)
					)
					(width 0)
					(fill yes)
				)
			)
		)
		(pad "2" smd custom
			(at 0 0.4445)
			(size 0.1524 0.1524)
			(layers "B.Cu" "B.Mask" "B.Paste")
			(net "GND")
			(options
				(clearance outline)
				(anchor circle)
			)
			(primitives
				(gr_poly
					(pts
						(arc
							(start 0.3048 0.2032)
							(mid 0.275042 0.275042)
							(end 0.2032 0.3048)
						)
						(arc
							(start -0.2032 0.3048)
							(mid -0.275042 0.275042)
							(end -0.3048 0.2032)
						)
						(arc
							(start -0.3048 -0.2032)
							(mid -0.275042 -0.275042)
							(end -0.2032 -0.3048)
						)
						(arc
							(start 0.2032 -0.3048)
							(mid 0.275042 -0.275042)
							(end 0.3048 -0.2032)
						)
					)
					(width 0)
					(fill yes)
				)
			)
		)
	)
	(footprint ""
		(layer "B.Cu")
		(at 95.377 -7.874 90)
		(property "Reference" "R37"
			(at 0 0 90)
			(layer "B.SilkS")
			(hide yes)
			(effects
				(font
					(size 1.27 1.27)
				)
				(justify mirror)
			)
		)
		(property "Value" "1MR2F-GP"
			(at -0.064008 -3.993896 90)
			(unlocked yes)
			(layer "B.Fab")
			(hide yes)
			(effects
				(font
					(size 1.016 1.016)
					(thickness 0.1524)
				)
				(justify mirror)
			)
		)
		(property "Device Type" "R402H16"
			(at -0.064008 -5.517896 90)
			(unlocked yes)
			(layer "B.Fab")
			(hide yes)
			(effects
				(font
					(size 1.016 1.016)
					(thickness 0.1524)
				)
				(justify mirror)
			)
		)
		(duplicate_pad_numbers_are_jumpers no)
		(fp_line
			(start 0.508 -0.9398)
			(end 0.508 0.9398)
			(stroke
				(width 0.1524)
				(type default)
			)
			(layer "B.SilkS")
		)
		(fp_line
			(start -0.508 -0.9398)
			(end 0.508 -0.9398)
			(stroke
				(width 0.1524)
				(type default)
			)
			(layer "B.SilkS")
		)
		(fp_rect
			(start 0.508 0.9398)
			(end -0.508 -0.9398)
			(stroke
				(width 0)
				(type default)
			)
			(fill no)
			(layer "B.CrtYd")
		)
		(fp_rect
			(start 0.508 0.9398)
			(end -0.508 -0.9398)
			(stroke
				(width 0)
				(type default)
			)
			(fill no)
			(layer "B.Fab")
		)
		(pad "1" smd custom
			(at 0 -0.4445 270)
			(size 0.1397 0.1397)
			(layers "B.Cu" "B.Mask" "B.Paste")
			(net "USB_CONN_GND")
			(options
				(clearance outline)
				(anchor circle)
			)
			(primitives
				(gr_poly
					(pts
						(arc
							(start -0.1778 0.2794)
							(mid -0.249642 0.249642)
							(end -0.2794 0.1778)
						)
						(arc
							(start -0.2794 -0.1778)
							(mid -0.249642 -0.249642)
							(end -0.1778 -0.2794)
						)
						(arc
							(start 0.1778 -0.2794)
							(mid 0.249642 -0.249642)
							(end 0.2794 -0.1778)
						)
						(arc
							(start 0.2794 0.1778)
							(mid 0.249642 0.249642)
							(end 0.1778 0.2794)
						)
					)
					(width 0)
					(fill yes)
				)
			)
		)
		(pad "2" smd custom
			(at 0 0.4445 270)
			(size 0.1397 0.1397)
			(layers "B.Cu" "B.Mask" "B.Paste")
			(net "GND")
			(options
				(clearance outline)
				(anchor circle)
			)
			(primitives
				(gr_poly
					(pts
						(arc
							(start -0.1778 0.2794)
							(mid -0.249642 0.249642)
							(end -0.2794 0.1778)
						)
						(arc
							(start -0.2794 -0.1778)
							(mid -0.249642 -0.249642)
							(end -0.1778 -0.2794)
						)
						(arc
							(start 0.1778 -0.2794)
							(mid 0.249642 -0.249642)
							(end 0.2794 -0.1778)
						)
						(arc
							(start 0.2794 0.1778)
							(mid 0.249642 0.249642)
							(end 0.1778 0.2794)
						)
					)
					(width 0)
					(fill yes)
				)
			)
		)
	)
	(footprint ""
		(layer "B.Cu")
		(at 41.4782 -134.3406 180)
		(property "Reference" "R373"
			(at 0 0 0)
			(layer "B.SilkS")
			(hide yes)
			(effects
				(font
					(size 1.27 1.27)
				)
				(justify mirror)
			)
		)
		(property "Value" "4K7R2F-GP"
			(at -0.064008 -3.993896 180)
			(unlocked yes)
			(layer "B.Fab")
			(hide yes)
			(effects
				(font
					(size 1.016 1.016)
					(thickness 0.1524)
				)
				(justify mirror)
			)
		)
		(property "Device Type" "R402H16"
			(at -0.064008 -5.517896 180)
			(unlocked yes)
			(layer "B.Fab")
			(hide yes)
			(effects
				(font
					(size 1.016 1.016)
					(thickness 0.1524)
				)
				(justify mirror)
			)
		)
		(duplicate_pad_numbers_are_jumpers no)
		(fp_line
			(start 0.508 -0.9398)
			(end 0.508 0.9398)
			(stroke
				(width 0.1524)
				(type default)
			)
			(layer "B.SilkS")
		)
		(fp_line
			(start -0.508 -0.9398)
			(end 0.508 -0.9398)
			(stroke
				(width 0.1524)
				(type default)
			)
			(layer "B.SilkS")
		)
		(fp_rect
			(start 0.508 0.9398)
			(end -0.508 -0.9398)
			(stroke
				(width 0)
				(type default)
			)
			(fill no)
			(layer "B.CrtYd")
		)
		(fp_rect
			(start 0.508 0.9398)
			(end -0.508 -0.9398)
			(stroke
				(width 0)
				(type default)
			)
			(fill no)
			(layer "B.Fab")
		)
		(pad "1" smd custom
			(at 0 -0.4445)
			(size 0.1397 0.1397)
			(layers "B.Cu" "B.Mask" "B.Paste")
			(net "P3V3_STBY")
			(options
				(clearance outline)
				(anchor circle)
			)
			(primitives
				(gr_poly
					(pts
						(arc
							(start -0.1778 0.2794)
							(mid -0.249642 0.249642)
							(end -0.2794 0.1778)
						)
						(arc
							(start -0.2794 -0.1778)
							(mid -0.249642 -0.249642)
							(end -0.1778 -0.2794)
						)
						(arc
							(start 0.1778 -0.2794)
							(mid 0.249642 -0.249642)
							(end 0.2794 -0.1778)
						)
						(arc
							(start 0.2794 0.1778)
							(mid 0.249642 0.249642)
							(end 0.1778 0.2794)
						)
					)
					(width 0)
					(fill yes)
				)
			)
		)
		(pad "2" smd custom
			(at 0 0.4445)
			(size 0.1397 0.1397)
			(layers "B.Cu" "B.Mask" "B.Paste")
			(net "BMC_GPIOS5")
			(options
				(clearance outline)
				(anchor circle)
			)
			(primitives
				(gr_poly
					(pts
						(arc
							(start -0.1778 0.2794)
							(mid -0.249642 0.249642)
							(end -0.2794 0.1778)
						)
						(arc
							(start -0.2794 -0.1778)
							(mid -0.249642 -0.249642)
							(end -0.1778 -0.2794)
						)
						(arc
							(start 0.1778 -0.2794)
							(mid 0.249642 -0.249642)
							(end 0.2794 -0.1778)
						)
						(arc
							(start 0.2794 0.1778)
							(mid 0.249642 0.249642)
							(end 0.1778 0.2794)
						)
					)
					(width 0)
					(fill yes)
				)
			)
		)
	)
)
